(kicad_pcb
	(version 20260206)
	(generator "pcbnew")
	(generator_version "10.0")
	(general
		(thickness 1.6)
		(legacy_teardrops no)
	)
	(paper "A4")
	(title_block
		(title "03242023_DA0F0TMBIJ0_F0T_Motherboard_J_brd_V01_OCP.brd")
		(comment 1 "Grand Teton / footprints 4495-4500 of 6105")
	)
	(layers
		(0 "F.Cu" signal "TOP")
		(4 "In1.Cu" signal "GND")
		(6 "In2.Cu" signal "IN1")
		(8 "In3.Cu" signal "GND1")
		(10 "In4.Cu" signal "IN2")
		(12 "In5.Cu" signal "GND2")
		(14 "In6.Cu" signal "IN3")
		(16 "In7.Cu" signal "GND3")
		(18 "In8.Cu" signal "VCC")
		(20 "In9.Cu" signal "VCC1")
		(22 "In10.Cu" signal "GND4")
		(24 "In11.Cu" signal "IN4")
		(26 "In12.Cu" signal "GND5")
		(28 "In13.Cu" signal "IN5")
		(30 "In14.Cu" signal "GND6")
		(32 "In15.Cu" signal "IN6")
		(34 "In16.Cu" signal "GND7")
		(2 "B.Cu" signal "BOTTOM")
		(9 "F.Adhes" user "F.Adhesive")
		(11 "B.Adhes" user "B.Adhesive")
		(13 "F.Paste" user "Package Geometry/Pastemask Top")
		(15 "B.Paste" user "Package Geometry/Pastemask Bottom")
		(5 "F.SilkS" user "Ref Des/Silkscreen Top")
		(7 "B.SilkS" user "Ref Des/Silkscreen Bottom")
		(1 "F.Mask" user "Board Geometry/Soldermask Top")
		(3 "B.Mask" user "Board Geometry/Soldermask Bottom")
		(17 "Dwgs.User" user "User.Drawings")
		(19 "Cmts.User" user "User.Comments")
		(21 "Eco1.User" user "User.Eco1")
		(23 "Eco2.User" user "User.Eco2")
		(25 "Edge.Cuts" user "Board Geometry/Outline")
		(27 "Margin" user)
		(31 "F.CrtYd" user "Package Geometry/Place Bound Top")
		(29 "B.CrtYd" user "Package Geometry/Place Bound Bottom")
		(35 "F.Fab" user "Ref Des/Assembly Top")
		(33 "B.Fab" user "Ref Des/Assembly Bottom")
	)
	(footprint ""
		(layer "B.Cu")
		(at 306.968398 -190.45047 90)
		(property "Reference" "R555"
			(at 0 0 90)
			(layer "B.SilkS")
			(hide yes)
			(effects
				(font
					(size 1.27 1.27)
				)
				(justify mirror)
			)
		)
		(property "Value" ""
			(at 0 0 90)
			(layer "B.Fab")
			(effects
				(font
					(size 1.27 1.27)
				)
				(justify mirror)
			)
		)
		(duplicate_pad_numbers_are_jumpers no)
		(fp_line
			(start 0.7874 -0.4064)
			(end -0.7874 -0.4064)
			(stroke
				(width 0.1524)
				(type default)
			)
			(layer "B.SilkS")
		)
		(fp_line
			(start -0.7874 -0.4064)
			(end -0.7874 0.4064)
			(stroke
				(width 0.1524)
				(type default)
			)
			(layer "B.SilkS")
		)
		(fp_line
			(start 0.7874 0.4064)
			(end 0.7874 -0.4064)
			(stroke
				(width 0.1524)
				(type default)
			)
			(layer "B.SilkS")
		)
		(fp_line
			(start -0.7874 0.4064)
			(end 0.7874 0.4064)
			(stroke
				(width 0.1524)
				(type default)
			)
			(layer "B.SilkS")
		)
		(fp_line
			(start 0.67945 -0.305054)
			(end 0.12065 -0.305054)
			(stroke
				(width 0.1)
				(type default)
			)
			(layer "B.Fab")
		)
		(fp_line
			(start 0.12065 -0.305054)
			(end 0.12065 -0.2794)
			(stroke
				(width 0.1)
				(type default)
			)
			(layer "B.Fab")
		)
		(fp_line
			(start -0.12065 -0.3048)
			(end -0.67945 -0.3048)
			(stroke
				(width 0.1)
				(type default)
			)
			(layer "B.Fab")
		)
		(fp_line
			(start -0.67945 -0.3048)
			(end -0.67945 0.3048)
			(stroke
				(width 0.1)
				(type default)
			)
			(layer "B.Fab")
		)
		(fp_line
			(start 0.12065 -0.2794)
			(end -0.12065 -0.2794)
			(stroke
				(width 0.1)
				(type default)
			)
			(layer "B.Fab")
		)
		(fp_line
			(start -0.12065 -0.2794)
			(end -0.12065 -0.3048)
			(stroke
				(width 0.1)
				(type default)
			)
			(layer "B.Fab")
		)
		(fp_line
			(start 0.12065 0.2794)
			(end 0.12065 0.3048)
			(stroke
				(width 0.1)
				(type default)
			)
			(layer "B.Fab")
		)
		(fp_line
			(start -0.120396 0.2794)
			(end 0.12065 0.2794)
			(stroke
				(width 0.1)
				(type default)
			)
			(layer "B.Fab")
		)
		(fp_line
			(start 0.67945 0.3048)
			(end 0.67945 -0.305054)
			(stroke
				(width 0.1)
				(type default)
			)
			(layer "B.Fab")
		)
		(fp_line
			(start 0.12065 0.3048)
			(end 0.67945 0.3048)
			(stroke
				(width 0.1)
				(type default)
			)
			(layer "B.Fab")
		)
		(fp_line
			(start -0.120396 0.3048)
			(end -0.120396 0.2794)
			(stroke
				(width 0.1)
				(type default)
			)
			(layer "B.Fab")
		)
		(fp_line
			(start -0.67945 0.3048)
			(end -0.120396 0.3048)
			(stroke
				(width 0.1)
				(type default)
			)
			(layer "B.Fab")
		)
		(pad "1" smd circle
			(at 0.40005 0 270)
			(size 0 0)
			(layers "B.Cu" "B.Mask" "B.Paste")
			(net "SVID_DIO1_CPU0_R")
		)
		(pad "2" smd circle
			(at -0.40005 0 270)
			(size 0 0)
			(layers "B.Cu" "B.Mask" "B.Paste")
			(net "PVNN_TERM_CPU0")
		)
	)
	(footprint ""
		(layer "B.Cu")
		(at 178.1556 -110.975394 -90)
		(property "Reference" "C1908"
			(at 0 0 90)
			(layer "B.SilkS")
			(hide yes)
			(effects
				(font
					(size 1.27 1.27)
				)
				(justify mirror)
			)
		)
		(property "Value" ""
			(at 0 0 90)
			(layer "B.Fab")
			(effects
				(font
					(size 1.27 1.27)
				)
				(justify mirror)
			)
		)
		(duplicate_pad_numbers_are_jumpers no)
		(fp_line
			(start -0.69215 0.2921)
			(end 0.69215 0.2921)
			(stroke
				(width 0.1524)
				(type default)
			)
			(layer "B.SilkS")
		)
		(fp_line
			(start 0.69215 0.2921)
			(end 0.69215 -0.2921)
			(stroke
				(width 0.1524)
				(type default)
			)
			(layer "B.SilkS")
		)
		(fp_line
			(start -0.69215 -0.2921)
			(end -0.69215 0.2921)
			(stroke
				(width 0.1524)
				(type default)
			)
			(layer "B.SilkS")
		)
		(fp_line
			(start 0.69215 -0.2921)
			(end -0.69215 -0.2921)
			(stroke
				(width 0.1524)
				(type default)
			)
			(layer "B.SilkS")
		)
		(fp_line
			(start -0.51435 0.2794)
			(end 0.51435 0.2794)
			(stroke
				(width 0.1)
				(type default)
			)
			(layer "B.Fab")
		)
		(fp_line
			(start 0.51435 0.2794)
			(end 0.51435 -0.2794)
			(stroke
				(width 0.1)
				(type default)
			)
			(layer "B.Fab")
		)
		(fp_line
			(start -0.51435 -0.2794)
			(end -0.51435 0.2794)
			(stroke
				(width 0.1)
				(type default)
			)
			(layer "B.Fab")
		)
		(fp_line
			(start 0.51435 -0.2794)
			(end -0.51435 -0.2794)
			(stroke
				(width 0.1)
				(type default)
			)
			(layer "B.Fab")
		)
		(pad "1" smd circle
			(at 0.40005 0 90)
			(size 0 0)
			(layers "B.Cu" "B.Mask" "B.Paste")
			(net "P3V3_AUX_FPGA_VCCIO4")
		)
		(pad "2" smd circle
			(at -0.40005 0 90)
			(size 0 0)
			(layers "B.Cu" "B.Mask" "B.Paste")
			(net "GND")
		)
		(zone
			(layer "B.Cu")
			(hatch none 0.5)
			(connect_pads
				(clearance 0)
			)
			(min_thickness 0.25)
			(keepout
				(tracks not_allowed)
				(vias allowed)
				(pads allowed)
				(copperpour not_allowed)
				(footprints allowed)
			)
			(placement
				(enabled no)
				(sheetname "")
			)
			(fill
				(thermal_gap 0.5)
				(thermal_bridge_width 0.5)
				(island_removal_mode 0)
			)
			(polygon
				(pts
					(xy 178.06797 -110.784894) (xy 178.009804 -110.876334) (xy 178.009804 -111.075724) (xy 178.06797 -111.165894)
					(xy 178.24323 -111.165894) (xy 178.30165 -111.075724) (xy 178.30165 -110.876334) (xy 178.243484 -110.784894)
				)
			)
		)
	)
	(footprint ""
		(layer "B.Cu")
		(at 193.384678 -126.405132 180)
		(property "Reference" "R4518"
			(at 0 0 0)
			(layer "B.SilkS")
			(hide yes)
			(effects
				(font
					(size 1.27 1.27)
				)
				(justify mirror)
			)
		)
		(property "Value" ""
			(at 0 0 0)
			(layer "B.Fab")
			(effects
				(font
					(size 1.27 1.27)
				)
				(justify mirror)
			)
		)
		(duplicate_pad_numbers_are_jumpers no)
		(fp_line
			(start 0.7874 0.4064)
			(end 0.7874 -0.4064)
			(stroke
				(width 0.1524)
				(type default)
			)
			(layer "B.SilkS")
		)
		(fp_line
			(start 0.7874 -0.4064)
			(end -0.7874 -0.4064)
			(stroke
				(width 0.1524)
				(type default)
			)
			(layer "B.SilkS")
		)
		(fp_line
			(start -0.7874 0.4064)
			(end 0.7874 0.4064)
			(stroke
				(width 0.1524)
				(type default)
			)
			(layer "B.SilkS")
		)
		(fp_line
			(start -0.7874 -0.4064)
			(end -0.7874 0.4064)
			(stroke
				(width 0.1524)
				(type default)
			)
			(layer "B.SilkS")
		)
		(fp_line
			(start 0.67945 0.3048)
			(end 0.67945 -0.305054)
			(stroke
				(width 0.1)
				(type default)
			)
			(layer "B.Fab")
		)
		(fp_line
			(start 0.67945 -0.305054)
			(end 0.12065 -0.305054)
			(stroke
				(width 0.1)
				(type default)
			)
			(layer "B.Fab")
		)
		(fp_line
			(start 0.12065 0.3048)
			(end 0.67945 0.3048)
			(stroke
				(width 0.1)
				(type default)
			)
			(layer "B.Fab")
		)
		(fp_line
			(start 0.12065 0.2794)
			(end 0.12065 0.3048)
			(stroke
				(width 0.1)
				(type default)
			)
			(layer "B.Fab")
		)
		(fp_line
			(start 0.12065 -0.2794)
			(end -0.12065 -0.2794)
			(stroke
				(width 0.1)
				(type default)
			)
			(layer "B.Fab")
		)
		(fp_line
			(start 0.12065 -0.305054)
			(end 0.12065 -0.2794)
			(stroke
				(width 0.1)
				(type default)
			)
			(layer "B.Fab")
		)
		(fp_line
			(start -0.120396 0.3048)
			(end -0.120396 0.2794)
			(stroke
				(width 0.1)
				(type default)
			)
			(layer "B.Fab")
		)
		(fp_line
			(start -0.120396 0.2794)
			(end 0.12065 0.2794)
			(stroke
				(width 0.1)
				(type default)
			)
			(layer "B.Fab")
		)
		(fp_line
			(start -0.12065 -0.2794)
			(end -0.12065 -0.3048)
			(stroke
				(width 0.1)
				(type default)
			)
			(layer "B.Fab")
		)
		(fp_line
			(start -0.12065 -0.3048)
			(end -0.67945 -0.3048)
			(stroke
				(width 0.1)
				(type default)
			)
			(layer "B.Fab")
		)
		(fp_line
			(start -0.67945 0.3048)
			(end -0.120396 0.3048)
			(stroke
				(width 0.1)
				(type default)
			)
			(layer "B.Fab")
		)
		(fp_line
			(start -0.67945 -0.3048)
			(end -0.67945 0.3048)
			(stroke
				(width 0.1)
				(type default)
			)
			(layer "B.Fab")
		)
		(pad "1" smd circle
			(at 0.40005 0)
			(size 0 0)
			(layers "B.Cu" "B.Mask" "B.Paste")
			(net "P3V3")
		)
		(pad "2" smd circle
			(at -0.40005 0)
			(size 0 0)
			(layers "B.Cu" "B.Mask" "B.Paste")
			(net "CLK_GPU_2_OE_N")
		)
	)
	(footprint ""
		(layer "B.Cu")
		(at 121.1326 -357.675688 180)
		(property "Reference" "PC2282"
			(at 0 0 0)
			(layer "B.SilkS")
			(hide yes)
			(effects
				(font
					(size 1.27 1.27)
				)
				(justify mirror)
			)
		)
		(property "Value" ""
			(at 0 0 0)
			(layer "B.Fab")
			(effects
				(font
					(size 1.27 1.27)
				)
				(justify mirror)
			)
		)
		(duplicate_pad_numbers_are_jumpers no)
		(fp_line
			(start 0.7874 0.4064)
			(end 0.7874 -0.4064)
			(stroke
				(width 0.1524)
				(type default)
			)
			(layer "B.SilkS")
		)
		(fp_line
			(start 0.7874 -0.4064)
			(end -0.7874 -0.4064)
			(stroke
				(width 0.1524)
				(type default)
			)
			(layer "B.SilkS")
		)
		(fp_line
			(start -0.7874 0.4064)
			(end 0.7874 0.4064)
			(stroke
				(width 0.1524)
				(type default)
			)
			(layer "B.SilkS")
		)
		(fp_line
			(start -0.7874 -0.4064)
			(end -0.7874 0.4064)
			(stroke
				(width 0.1524)
				(type default)
			)
			(layer "B.SilkS")
		)
		(fp_line
			(start 0.67945 0.3048)
			(end 0.67945 -0.305054)
			(stroke
				(width 0.1)
				(type default)
			)
			(layer "B.Fab")
		)
		(fp_line
			(start 0.67945 -0.305054)
			(end 0.12065 -0.305054)
			(stroke
				(width 0.1)
				(type default)
			)
			(layer "B.Fab")
		)
		(fp_line
			(start 0.12065 0.3048)
			(end 0.67945 0.3048)
			(stroke
				(width 0.1)
				(type default)
			)
			(layer "B.Fab")
		)
		(fp_line
			(start 0.12065 0.2794)
			(end 0.12065 0.3048)
			(stroke
				(width 0.1)
				(type default)
			)
			(layer "B.Fab")
		)
		(fp_line
			(start 0.12065 -0.2794)
			(end -0.12065 -0.2794)
			(stroke
				(width 0.1)
				(type default)
			)
			(layer "B.Fab")
		)
		(fp_line
			(start 0.12065 -0.305054)
			(end 0.12065 -0.2794)
			(stroke
				(width 0.1)
				(type default)
			)
			(layer "B.Fab")
		)
		(fp_line
			(start -0.120396 0.3048)
			(end -0.120396 0.2794)
			(stroke
				(width 0.1)
				(type default)
			)
			(layer "B.Fab")
		)
		(fp_line
			(start -0.120396 0.2794)
			(end 0.12065 0.2794)
			(stroke
				(width 0.1)
				(type default)
			)
			(layer "B.Fab")
		)
		(fp_line
			(start -0.12065 -0.2794)
			(end -0.12065 -0.3048)
			(stroke
				(width 0.1)
				(type default)
			)
			(layer "B.Fab")
		)
		(fp_line
			(start -0.12065 -0.3048)
			(end -0.67945 -0.3048)
			(stroke
				(width 0.1)
				(type default)
			)
			(layer "B.Fab")
		)
		(fp_line
			(start -0.67945 0.3048)
			(end -0.120396 0.3048)
			(stroke
				(width 0.1)
				(type default)
			)
			(layer "B.Fab")
		)
		(fp_line
			(start -0.67945 -0.3048)
			(end -0.67945 0.3048)
			(stroke
				(width 0.1)
				(type default)
			)
			(layer "B.Fab")
		)
		(pad "1" smd circle
			(at 0.40005 0)
			(size 0 0)
			(layers "B.Cu" "B.Mask" "B.Paste")
			(net "SH_PVPP_HBM_CPU1_P")
		)
		(pad "2" smd circle
			(at -0.40005 0)
			(size 0 0)
			(layers "B.Cu" "B.Mask" "B.Paste")
			(net "SH_PVPP_HBM_CPU1_N")
		)
	)
	(footprint ""
		(layer "B.Cu")
		(at 173.04893 -102.707948)
		(property "Reference" "C1947"
			(at 0 0 0)
			(layer "B.SilkS")
			(hide yes)
			(effects
				(font
					(size 1.27 1.27)
				)
				(justify mirror)
			)
		)
		(property "Value" ""
			(at 0 0 0)
			(layer "B.Fab")
			(effects
				(font
					(size 1.27 1.27)
				)
				(justify mirror)
			)
		)
		(duplicate_pad_numbers_are_jumpers no)
		(fp_line
			(start -0.7874 -0.4064)
			(end -0.7874 0.4064)
			(stroke
				(width 0.1524)
				(type default)
			)
			(layer "B.SilkS")
		)
		(fp_line
			(start -0.7874 0.4064)
			(end 0.7874 0.4064)
			(stroke
				(width 0.1524)
				(type default)
			)
			(layer "B.SilkS")
		)
		(fp_line
			(start 0.7874 -0.4064)
			(end -0.7874 -0.4064)
			(stroke
				(width 0.1524)
				(type default)
			)
			(layer "B.SilkS")
		)
		(fp_line
			(start 0.7874 0.4064)
			(end 0.7874 -0.4064)
			(stroke
				(width 0.1524)
				(type default)
			)
			(layer "B.SilkS")
		)
		(fp_line
			(start -0.67945 -0.3048)
			(end -0.67945 0.3048)
			(stroke
				(width 0.1)
				(type default)
			)
			(layer "B.Fab")
		)
		(fp_line
			(start -0.67945 0.3048)
			(end -0.120396 0.3048)
			(stroke
				(width 0.1)
				(type default)
			)
			(layer "B.Fab")
		)
		(fp_line
			(start -0.12065 -0.3048)
			(end -0.67945 -0.3048)
			(stroke
				(width 0.1)
				(type default)
			)
			(layer "B.Fab")
		)
		(fp_line
			(start -0.12065 -0.2794)
			(end -0.12065 -0.3048)
			(stroke
				(width 0.1)
				(type default)
			)
			(layer "B.Fab")
		)
		(fp_line
			(start -0.120396 0.2794)
			(end 0.12065 0.2794)
			(stroke
				(width 0.1)
				(type default)
			)
			(layer "B.Fab")
		)
		(fp_line
			(start -0.120396 0.3048)
			(end -0.120396 0.2794)
			(stroke
				(width 0.1)
				(type default)
			)
			(layer "B.Fab")
		)
		(fp_line
			(start 0.12065 -0.305054)
			(end 0.12065 -0.2794)
			(stroke
				(width 0.1)
				(type default)
			)
			(layer "B.Fab")
		)
		(fp_line
			(start 0.12065 -0.2794)
			(end -0.12065 -0.2794)
			(stroke
				(width 0.1)
				(type default)
			)
			(layer "B.Fab")
		)
		(fp_line
			(start 0.12065 0.2794)
			(end 0.12065 0.3048)
			(stroke
				(width 0.1)
				(type default)
			)
			(layer "B.Fab")
		)
		(fp_line
			(start 0.12065 0.3048)
			(end 0.67945 0.3048)
			(stroke
				(width 0.1)
				(type default)
			)
			(layer "B.Fab")
		)
		(fp_line
			(start 0.67945 -0.305054)
			(end 0.12065 -0.305054)
			(stroke
				(width 0.1)
				(type default)
			)
			(layer "B.Fab")
		)
		(fp_line
			(start 0.67945 0.3048)
			(end 0.67945 -0.305054)
			(stroke
				(width 0.1)
				(type default)
			)
			(layer "B.Fab")
		)
		(pad "1" smd circle
			(at 0.40005 0 180)
			(size 0 0)
			(layers "B.Cu" "B.Mask" "B.Paste")
			(net "P3V3_AUX_FPGA_VCCIO5")
		)
		(pad "2" smd circle
			(at -0.40005 0 180)
			(size 0 0)
			(layers "B.Cu" "B.Mask" "B.Paste")
			(net "GND")
		)
	)
	(footprint ""
		(layer "B.Cu")
		(at 80.430624 -184.096152 -90)
		(property "Reference" "R240"
			(at 0 0 90)
			(layer "B.SilkS")
			(hide yes)
			(effects
				(font
					(size 1.27 1.27)
				)
				(justify mirror)
			)
		)
		(property "Value" ""
			(at 0 0 90)
			(layer "B.Fab")
			(effects
				(font
					(size 1.27 1.27)
				)
				(justify mirror)
			)
		)
		(duplicate_pad_numbers_are_jumpers no)
		(fp_line
			(start -0.7874 0.4064)
			(end 0.7874 0.4064)
			(stroke
				(width 0.1524)
				(type default)
			)
			(layer "B.SilkS")
		)
		(fp_line
			(start 0.7874 0.4064)
			(end 0.7874 -0.4064)
			(stroke
				(width 0.1524)
				(type default)
			)
			(layer "B.SilkS")
		)
		(fp_line
			(start -0.7874 -0.4064)
			(end -0.7874 0.4064)
			(stroke
				(width 0.1524)
				(type default)
			)
			(layer "B.SilkS")
		)
		(fp_line
			(start 0.7874 -0.4064)
			(end -0.7874 -0.4064)
			(stroke
				(width 0.1524)
				(type default)
			)
			(layer "B.SilkS")
		)
		(fp_line
			(start -0.67945 0.3048)
			(end -0.120396 0.3048)
			(stroke
				(width 0.1)
				(type default)
			)
			(layer "B.Fab")
		)
		(fp_line
			(start -0.120396 0.3048)
			(end -0.120396 0.2794)
			(stroke
				(width 0.1)
				(type default)
			)
			(layer "B.Fab")
		)
		(fp_line
			(start 0.12065 0.3048)
			(end 0.67945 0.3048)
			(stroke
				(width 0.1)
				(type default)
			)
			(layer "B.Fab")
		)
		(fp_line
			(start 0.67945 0.3048)
			(end 0.67945 -0.305054)
			(stroke
				(width 0.1)
				(type default)
			)
			(layer "B.Fab")
		)
		(fp_line
			(start -0.120396 0.2794)
			(end 0.12065 0.2794)
			(stroke
				(width 0.1)
				(type default)
			)
			(layer "B.Fab")
		)
		(fp_line
			(start 0.12065 0.2794)
			(end 0.12065 0.3048)
			(stroke
				(width 0.1)
				(type default)
			)
			(layer "B.Fab")
		)
		(fp_line
			(start -0.12065 -0.2794)
			(end -0.12065 -0.3048)
			(stroke
				(width 0.1)
				(type default)
			)
			(layer "B.Fab")
		)
		(fp_line
			(start 0.12065 -0.2794)
			(end -0.12065 -0.2794)
			(stroke
				(width 0.1)
				(type default)
			)
			(layer "B.Fab")
		)
		(fp_line
			(start -0.67945 -0.3048)
			(end -0.67945 0.3048)
			(stroke
				(width 0.1)
				(type default)
			)
			(layer "B.Fab")
		)
		(fp_line
			(start -0.12065 -0.3048)
			(end -0.67945 -0.3048)
			(stroke
				(width 0.1)
				(type default)
			)
			(layer "B.Fab")
		)
		(fp_line
			(start 0.12065 -0.305054)
			(end 0.12065 -0.2794)
			(stroke
				(width 0.1)
				(type default)
			)
			(layer "B.Fab")
		)
		(fp_line
			(start 0.67945 -0.305054)
			(end 0.12065 -0.305054)
			(stroke
				(width 0.1)
				(type default)
			)
			(layer "B.Fab")
		)
		(pad "1" smd circle
			(at 0.40005 0 90)
			(size 0 0)
			(layers "B.Cu" "B.Mask" "B.Paste")
			(net "H_CPU1_PROCHOT_LVC1_R_N")
		)
		(pad "2" smd circle
			(at -0.40005 0 90)
			(size 0 0)
			(layers "B.Cu" "B.Mask" "B.Paste")
			(net "H_CPU1_PROCHOT_LVC1_N")
		)
	)
)
